# SCM (Grand Teton) — schematic netlist excerpt (pin names and nets, part order shuffled) for the footprints in the layout excerpt that follows; sources: Cadence DE-HDL packaged netlist, KiCad conversion of 12092022_DA0F0TMDCD0_F0T_Management_Board_D_brd_V3_OCP.brd

R658  Q_RES  10K 1% EMPTY  pkg 0402LF  page 21 : A = P3V3_AUX ; B = EMMC_DT3_R
R87  Q_RES  150 1% CHIP  pkg 0402LF  page 23 : A = V_DACB_IO ; B = GND

(kicad_pcb
	(version 20260206)
	(generator "pcbnew")
	(generator_version "10.0")
	(general
		(thickness 1.6)
		(legacy_teardrops no)
	)
	(paper "A4")
	(title_block
		(title "12092022_DA0F0TMDCD0_F0T_Management_Board_D_brd_V3_OCP.brd")
		(comment 1 "Grand Teton / footprints 703-704 of 1440")
	)
	(layers
		(0 "F.Cu" signal "TOP")
		(4 "In1.Cu" signal "GND")
		(6 "In2.Cu" signal "IN1")
		(8 "In3.Cu" signal "GND1")
		(10 "In4.Cu" signal "IN2")
		(12 "In5.Cu" signal "VCC")
		(14 "In6.Cu" signal "VCC1")
		(16 "In7.Cu" signal "IN3")
		(18 "In8.Cu" signal "GND2")
		(20 "In9.Cu" signal "IN4")
		(22 "In10.Cu" signal "GND3")
		(2 "B.Cu" signal "BOTTOM")
		(9 "F.Adhes" user "F.Adhesive")
		(11 "B.Adhes" user "B.Adhesive")
		(13 "F.Paste" user "Package Geometry/Pastemask Top")
		(15 "B.Paste" user "Package Geometry/Pastemask Bottom")
		(5 "F.SilkS" user "Ref Des/Silkscreen Top")
		(7 "B.SilkS" user "Ref Des/Silkscreen Bottom")
		(1 "F.Mask" user "Board Geometry/Soldermask Top")
		(3 "B.Mask" user "Board Geometry/Soldermask Bottom")
		(17 "Dwgs.User" user "User.Drawings")
		(19 "Cmts.User" user "User.Comments")
		(21 "Eco1.User" user "User.Eco1")
		(23 "Eco2.User" user "User.Eco2")
		(25 "Edge.Cuts" user "Board Geometry/Outline")
		(27 "Margin" user)
		(31 "F.CrtYd" user "Package Geometry/Place Bound Top")
		(29 "B.CrtYd" user "Package Geometry/Place Bound Bottom")
		(35 "F.Fab" user "Ref Des/Assembly Top")
		(33 "B.Fab" user "Ref Des/Assembly Bottom")
	)
	(footprint ""
		(layer "F.Cu")
		(at 31.983172 -83.816952 -90)
		(property "Reference" "R658"
			(at 0 0 270)
			(layer "F.SilkS")
			(hide yes)
			(effects
				(font
					(size 1.27 1.27)
				)
			)
		)
		(property "Value" ""
			(at 0 0 270)
			(layer "F.Fab")
			(effects
				(font
					(size 1.27 1.27)
				)
			)
		)
		(duplicate_pad_numbers_are_jumpers no)
		(fp_line
			(start -0.7874 0.4064)
			(end -0.7874 -0.4064)
			(stroke
				(width 0.1524)
				(type default)
			)
			(layer "F.SilkS")
		)
		(fp_line
			(start 0.7874 0.4064)
			(end -0.7874 0.4064)
			(stroke
				(width 0.1524)
				(type default)
			)
			(layer "F.SilkS")
		)
		(fp_line
			(start -0.7874 -0.4064)
			(end 0.7874 -0.4064)
			(stroke
				(width 0.1524)
				(type default)
			)
			(layer "F.SilkS")
		)
		(fp_line
			(start 0.7874 -0.4064)
			(end 0.7874 0.4064)
			(stroke
				(width 0.1524)
				(type default)
			)
			(layer "F.SilkS")
		)
		(fp_line
			(start -0.67945 0.3048)
			(end -0.67945 -0.305054)
			(stroke
				(width 0.1)
				(type default)
			)
			(layer "F.Fab")
		)
		(fp_line
			(start -0.12065 0.3048)
			(end -0.67945 0.3048)
			(stroke
				(width 0.1)
				(type default)
			)
			(layer "F.Fab")
		)
		(fp_line
			(start 0.120396 0.3048)
			(end 0.120396 0.2794)
			(stroke
				(width 0.1)
				(type default)
			)
			(layer "F.Fab")
		)
		(fp_line
			(start 0.67945 0.3048)
			(end 0.120396 0.3048)
			(stroke
				(width 0.1)
				(type default)
			)
			(layer "F.Fab")
		)
		(fp_line
			(start -0.12065 0.2794)
			(end -0.12065 0.3048)
			(stroke
				(width 0.1)
				(type default)
			)
			(layer "F.Fab")
		)
		(fp_line
			(start 0.120396 0.2794)
			(end -0.12065 0.2794)
			(stroke
				(width 0.1)
				(type default)
			)
			(layer "F.Fab")
		)
		(fp_line
			(start -0.12065 -0.2794)
			(end 0.12065 -0.2794)
			(stroke
				(width 0.1)
				(type default)
			)
			(layer "F.Fab")
		)
		(fp_line
			(start 0.12065 -0.2794)
			(end 0.12065 -0.3048)
			(stroke
				(width 0.1)
				(type default)
			)
			(layer "F.Fab")
		)
		(fp_line
			(start 0.12065 -0.3048)
			(end 0.67945 -0.3048)
			(stroke
				(width 0.1)
				(type default)
			)
			(layer "F.Fab")
		)
		(fp_line
			(start 0.67945 -0.3048)
			(end 0.67945 0.3048)
			(stroke
				(width 0.1)
				(type default)
			)
			(layer "F.Fab")
		)
		(fp_line
			(start -0.67945 -0.305054)
			(end -0.12065 -0.305054)
			(stroke
				(width 0.1)
				(type default)
			)
			(layer "F.Fab")
		)
		(fp_line
			(start -0.12065 -0.305054)
			(end -0.12065 -0.2794)
			(stroke
				(width 0.1)
				(type default)
			)
			(layer "F.Fab")
		)
		(pad "1" smd circle
			(at -0.40005 0 270)
			(size 0 0)
			(layers "F.Cu" "F.Mask" "F.Paste")
			(net "P3V3_AUX")
		)
		(pad "2" smd circle
			(at 0.40005 0 270)
			(size 0 0)
			(layers "F.Cu" "F.Mask" "F.Paste")
			(net "EMMC_DT3_R")
		)
	)
	(footprint ""
		(layer "F.Cu")
		(at 31.75 -28.956)
		(property "Reference" "R87"
			(at 0 0 0)
			(layer "F.SilkS")
			(hide yes)
			(effects
				(font
					(size 1.27 1.27)
				)
			)
		)
		(property "Value" ""
			(at 0 0 0)
			(layer "F.Fab")
			(effects
				(font
					(size 1.27 1.27)
				)
			)
		)
		(duplicate_pad_numbers_are_jumpers no)
		(fp_line
			(start -0.7874 -0.4064)
			(end 0.7874 -0.4064)
			(stroke
				(width 0.1524)
				(type default)
			)
			(layer "F.SilkS")
		)
		(fp_line
			(start -0.7874 0.4064)
			(end -0.7874 -0.4064)
			(stroke
				(width 0.1524)
				(type default)
			)
			(layer "F.SilkS")
		)
		(fp_line
			(start 0.7874 -0.4064)
			(end 0.7874 0.4064)
			(stroke
				(width 0.1524)
				(type default)
			)
			(layer "F.SilkS")
		)
		(fp_line
			(start 0.7874 0.4064)
			(end -0.7874 0.4064)
			(stroke
				(width 0.1524)
				(type default)
			)
			(layer "F.SilkS")
		)
		(fp_line
			(start -0.67945 -0.305054)
			(end -0.12065 -0.305054)
			(stroke
				(width 0.1)
				(type default)
			)
			(layer "F.Fab")
		)
		(fp_line
			(start -0.67945 0.3048)
			(end -0.67945 -0.305054)
			(stroke
				(width 0.1)
				(type default)
			)
			(layer "F.Fab")
		)
		(fp_line
			(start -0.12065 -0.305054)
			(end -0.12065 -0.2794)
			(stroke
				(width 0.1)
				(type default)
			)
			(layer "F.Fab")
		)
		(fp_line
			(start -0.12065 -0.2794)
			(end 0.12065 -0.2794)
			(stroke
				(width 0.1)
				(type default)
			)
			(layer "F.Fab")
		)
		(fp_line
			(start -0.12065 0.2794)
			(end -0.12065 0.3048)
			(stroke
				(width 0.1)
				(type default)
			)
			(layer "F.Fab")
		)
		(fp_line
			(start -0.12065 0.3048)
			(end -0.67945 0.3048)
			(stroke
				(width 0.1)
				(type default)
			)
			(layer "F.Fab")
		)
		(fp_line
			(start 0.120396 0.2794)
			(end -0.12065 0.2794)
			(stroke
				(width 0.1)
				(type default)
			)
			(layer "F.Fab")
		)
		(fp_line
			(start 0.120396 0.3048)
			(end 0.120396 0.2794)
			(stroke
				(width 0.1)
				(type default)
			)
			(layer "F.Fab")
		)
		(fp_line
			(start 0.12065 -0.3048)
			(end 0.67945 -0.3048)
			(stroke
				(width 0.1)
				(type default)
			)
			(layer "F.Fab")
		)
		(fp_line
			(start 0.12065 -0.2794)
			(end 0.12065 -0.3048)
			(stroke
				(width 0.1)
				(type default)
			)
			(layer "F.Fab")
		)
		(fp_line
			(start 0.67945 -0.3048)
			(end 0.67945 0.3048)
			(stroke
				(width 0.1)
				(type default)
			)
			(layer "F.Fab")
		)
		(fp_line
			(start 0.67945 0.3048)
			(end 0.120396 0.3048)
			(stroke
				(width 0.1)
				(type default)
			)
			(layer "F.Fab")
		)
		(pad "1" smd circle
			(at -0.40005 0)
			(size 0 0)
			(layers "F.Cu" "F.Mask" "F.Paste")
			(net "V_DACB_IO")
		)
		(pad "2" smd circle
			(at 0.40005 0)
			(size 0 0)
			(layers "F.Cu" "F.Mask" "F.Paste")
			(net "GND")
		)
	)
)
